(kicad_pcb
	(version 20260206)
	(generator "pcbnew")
	(generator_version "10.0")
	(general
		(thickness 1.6)
		(legacy_teardrops no)
	)
	(paper "A4")
	(title_block
		(title "peb — Lightning_PEB_BRD.brd")
		(comment 1 "Lightning (Wiwynn / Facebook NVMe JBOF) / footprints 523-528 of 2563")
	)
	(layers
		(0 "F.Cu" signal "TOP")
		(4 "In1.Cu" signal "L2GND")
		(6 "In2.Cu" signal "L3")
		(8 "In3.Cu" signal "L4VCC")
		(10 "In4.Cu" signal "L5VCC")
		(12 "In5.Cu" signal "L6")
		(14 "In6.Cu" signal "L7GND")
		(2 "B.Cu" signal "BOTTOM")
		(9 "F.Adhes" user "F.Adhesive")
		(11 "B.Adhes" user "B.Adhesive")
		(13 "F.Paste" user "Package Geometry/Pastemask Top")
		(15 "B.Paste" user "Package Geometry/Pastemask Bottom")
		(5 "F.SilkS" user "Ref Des/Silkscreen Top")
		(7 "B.SilkS" user "Ref Des/Silkscreen Bottom")
		(1 "F.Mask" user "Board Geometry/Soldermask Top")
		(3 "B.Mask" user "Board Geometry/Soldermask Bottom")
		(17 "Dwgs.User" user "User.Drawings")
		(19 "Cmts.User" user "User.Comments")
		(21 "Eco1.User" user "User.Eco1")
		(23 "Eco2.User" user "User.Eco2")
		(25 "Edge.Cuts" user "Board Geometry/Outline")
		(27 "Margin" user)
		(31 "F.CrtYd" user "Package Geometry/Place Bound Top")
		(29 "B.CrtYd" user "Package Geometry/Place Bound Bottom")
		(35 "F.Fab" user "Ref Des/Assembly Top")
		(33 "B.Fab" user "Ref Des/Assembly Bottom")
	)
	(footprint ""
		(layer "F.Cu")
		(at 335.185512 -178.782218)
		(property "Reference" "U201"
			(at 0 0 0)
			(layer "F.SilkS")
			(hide yes)
			(effects
				(font
					(size 1.27 1.27)
				)
			)
		)
		(property "Value" "MAX7311AUG-GP"
			(at 0 -12.1412 0)
			(unlocked yes)
			(layer "F.Fab")
			(hide yes)
			(effects
				(font
					(size 1.016 1.016)
					(thickness 0.1524)
				)
			)
		)
		(property "Device Type" "TSOIC24H44"
			(at 0 -13.6652 0)
			(unlocked yes)
			(layer "F.Fab")
			(hide yes)
			(effects
				(font
					(size 1.016 1.016)
					(thickness 0.1524)
				)
			)
		)
		(duplicate_pad_numbers_are_jumpers no)
		(fp_line
			(start -4.1148 -1.778)
			(end -4.1148 1.778)
			(stroke
				(width 0.1524)
				(type default)
			)
			(layer "F.SilkS")
		)
		(fp_line
			(start -4.1148 -1.778)
			(end 3.683 -1.778)
			(stroke
				(width 0.1524)
				(type default)
			)
			(layer "F.SilkS")
		)
		(fp_line
			(start -4.0386 1.778)
			(end -4.0386 3.556)
			(stroke
				(width 0.3556)
				(type default)
			)
			(layer "F.SilkS")
		)
		(fp_line
			(start -3.8354 0)
			(end -4.1148 -0.2794)
			(stroke
				(width 0.1524)
				(type default)
			)
			(layer "F.SilkS")
		)
		(fp_line
			(start -3.8354 0)
			(end -4.1148 0.2794)
			(stroke
				(width 0.1524)
				(type default)
			)
			(layer "F.SilkS")
		)
		(fp_line
			(start 3.683 -1.778)
			(end 3.683 1.778)
			(stroke
				(width 0.1524)
				(type default)
			)
			(layer "F.SilkS")
		)
		(fp_line
			(start 3.683 1.778)
			(end -4.1148 1.778)
			(stroke
				(width 0.1524)
				(type default)
			)
			(layer "F.SilkS")
		)
		(fp_poly
			(pts
				(xy -3.7592 -1.778) (xy 3.683 -1.778) (xy 3.683 1.778) (xy -3.7592 1.778)
			)
			(stroke
				(width 0)
				(type default)
			)
			(fill yes)
			(layer "F.SilkS")
		)
		(fp_poly
			(pts
				(xy -4.22656 3.81) (xy 4.22656 3.81) (xy 4.22656 -3.81) (xy -4.22656 -3.81)
			)
			(stroke
				(width 0)
				(type default)
			)
			(fill no)
			(layer "F.CrtYd")
		)
		(fp_poly
			(pts
				(xy -4.22656 -3.81) (xy 4.22656 -3.81) (xy 4.22656 3.81) (xy -4.22656 3.81)
			)
			(stroke
				(width 0)
				(type default)
			)
			(fill no)
			(layer "F.Fab")
		)
		(pad "1" smd rect
			(at -3.57632 2.8194)
			(size 0.3556 1.524)
			(layers "F.Cu" "F.Mask" "F.Paste")
			(net "IOEXP_INT#_4")
		)
		(pad "2" smd rect
			(at -2.92608 2.8194)
			(size 0.3556 1.524)
			(layers "F.Cu" "F.Mask" "F.Paste")
			(net "IOEXP4_AD1")
		)
		(pad "3" smd rect
			(at -2.27584 2.8194)
			(size 0.3556 1.524)
			(layers "F.Cu" "F.Mask" "F.Paste")
			(net "IOEXP4_AD2")
		)
		(pad "4" smd rect
			(at -1.6256 2.8194)
			(size 0.3556 1.524)
			(layers "F.Cu" "F.Mask" "F.Paste")
			(net "SSD_PRSNT#4")
		)
		(pad "5" smd rect
			(at -0.97536 2.8194)
			(size 0.3556 1.524)
			(layers "F.Cu" "F.Mask" "F.Paste")
			(net "SSD_ATNLED#4")
		)
		(pad "6" smd rect
			(at -0.32512 2.8194)
			(size 0.3556 1.524)
			(layers "F.Cu" "F.Mask" "F.Paste")
			(net "SSD_PWREN4")
		)
		(pad "7" smd rect
			(at 0.32512 2.8194)
			(size 0.3556 1.524)
			(layers "F.Cu" "F.Mask" "F.Paste")
			(net "SSD_PERST#4")
		)
		(pad "8" smd rect
			(at 0.97536 2.8194)
			(size 0.3556 1.524)
			(layers "F.Cu" "F.Mask" "F.Paste")
			(net "SSD_PRSNT#9")
		)
		(pad "9" smd rect
			(at 1.6256 2.8194)
			(size 0.3556 1.524)
			(layers "F.Cu" "F.Mask" "F.Paste")
			(net "SSD_ATNLED#9")
		)
		(pad "10" smd rect
			(at 2.27584 2.8194)
			(size 0.3556 1.524)
			(layers "F.Cu" "F.Mask" "F.Paste")
			(net "SSD_PWREN9")
		)
		(pad "11" smd rect
			(at 2.92608 2.8194)
			(size 0.3556 1.524)
			(layers "F.Cu" "F.Mask" "F.Paste")
			(net "SSD_PERST#9")
		)
		(pad "12" smd rect
			(at 3.57632 2.8194)
			(size 0.3556 1.524)
			(layers "F.Cu" "F.Mask" "F.Paste")
			(net "GND")
		)
		(pad "13" smd rect
			(at 3.57632 -2.8194)
			(size 0.3556 1.524)
			(layers "F.Cu" "F.Mask" "F.Paste")
			(net "SSD_PRSNT#14")
		)
		(pad "14" smd rect
			(at 2.92608 -2.8194)
			(size 0.3556 1.524)
			(layers "F.Cu" "F.Mask" "F.Paste")
			(net "SSD_ATNLED#14")
		)
		(pad "15" smd rect
			(at 2.27584 -2.8194)
			(size 0.3556 1.524)
			(layers "F.Cu" "F.Mask" "F.Paste")
			(net "SSD_PWREN14")
		)
		(pad "16" smd rect
			(at 1.6256 -2.8194)
			(size 0.3556 1.524)
			(layers "F.Cu" "F.Mask" "F.Paste")
			(net "SSD_PERST#14")
		)
		(pad "17" smd rect
			(at 0.97536 -2.8194)
			(size 0.3556 1.524)
			(layers "F.Cu" "F.Mask" "F.Paste")
			(net "IOEXP4_GPIO12")
		)
		(pad "18" smd rect
			(at 0.32512 -2.8194)
			(size 0.3556 1.524)
			(layers "F.Cu" "F.Mask" "F.Paste")
			(net "IOEXP4_GPIO13")
		)
		(pad "19" smd rect
			(at -0.32512 -2.8194)
			(size 0.3556 1.524)
			(layers "F.Cu" "F.Mask" "F.Paste")
			(net "IOEXP4_GPIO14")
		)
		(pad "20" smd rect
			(at -0.97536 -2.8194)
			(size 0.3556 1.524)
			(layers "F.Cu" "F.Mask" "F.Paste")
			(net "BMC_PERST#15")
		)
		(pad "21" smd rect
			(at -1.6256 -2.8194)
			(size 0.3556 1.524)
			(layers "F.Cu" "F.Mask" "F.Paste")
			(net "IOEXP4_AD0")
		)
		(pad "22" smd rect
			(at -2.27584 -2.8194)
			(size 0.3556 1.524)
			(layers "F.Cu" "F.Mask" "F.Paste")
			(net "I2C_GPIO_SCL_4")
		)
		(pad "23" smd rect
			(at -2.92608 -2.8194)
			(size 0.3556 1.524)
			(layers "F.Cu" "F.Mask" "F.Paste")
			(net "I2C_GPIO_SDA_4")
		)
		(pad "24" smd rect
			(at -3.57632 -2.8194)
			(size 0.3556 1.524)
			(layers "F.Cu" "F.Mask" "F.Paste")
			(net "P3V3_STBY")
		)
	)
	(footprint ""
		(layer "F.Cu")
		(at 26.621232 -102.182168)
		(property "Reference" "U42"
			(at 0 0 0)
			(layer "F.SilkS")
			(hide yes)
			(effects
				(font
					(size 1.27 1.27)
				)
			)
		)
		(property "Value" "SN74LVC1G07DCKRG4-2-GP"
			(at -2.3368 -8.6868 0)
			(unlocked yes)
			(layer "F.Fab")
			(hide yes)
			(effects
				(font
					(size 1.016 1.016)
					(thickness 0.1524)
				)
			)
		)
		(property "Device Type" "SC70-5H44"
			(at -2.3114 -10.414 0)
			(unlocked yes)
			(layer "F.Fab")
			(hide yes)
			(effects
				(font
					(size 1.016 1.016)
					(thickness 0.1524)
				)
			)
		)
		(duplicate_pad_numbers_are_jumpers no)
		(fp_line
			(start -1.27 -1.7018)
			(end 1.27 -1.7018)
			(stroke
				(width 0.1524)
				(type default)
			)
			(layer "F.SilkS")
		)
		(fp_line
			(start -1.27 1.7018)
			(end -1.27 -1.7018)
			(stroke
				(width 0.1524)
				(type default)
			)
			(layer "F.SilkS")
		)
		(fp_line
			(start 0.6604 -1.8034)
			(end 1.3843 -1.8034)
			(stroke
				(width 0.3302)
				(type default)
			)
			(layer "F.SilkS")
		)
		(fp_line
			(start 1.27 -1.7018)
			(end 1.27 1.7018)
			(stroke
				(width 0.1524)
				(type default)
			)
			(layer "F.SilkS")
		)
		(fp_line
			(start 1.27 1.7018)
			(end -1.27 1.7018)
			(stroke
				(width 0.1524)
				(type default)
			)
			(layer "F.SilkS")
		)
		(fp_line
			(start 1.3843 -1.8034)
			(end 1.3843 -1.1176)
			(stroke
				(width 0.3302)
				(type default)
			)
			(layer "F.SilkS")
		)
		(fp_rect
			(start -1.524 1.9558)
			(end 1.524 -1.9558)
			(stroke
				(width 0)
				(type default)
			)
			(fill no)
			(layer "F.CrtYd")
		)
		(fp_poly
			(pts
				(xy -1.524 -1.9558) (xy 1.524 -1.9558) (xy 1.524 1.9558) (xy -1.524 1.9558)
			)
			(stroke
				(width 0)
				(type default)
			)
			(fill no)
			(layer "F.Fab")
		)
		(pad "1" smd rect
			(at 0.65024 -0.8255)
			(size 0.4064 1.2192)
			(layers "F.Cu" "F.Mask" "F.Paste")
			(net "Net_285")
		)
		(pad "2" smd rect
			(at 0 -0.8255)
			(size 0.4064 1.2192)
			(layers "F.Cu" "F.Mask" "F.Paste")
			(net "FM_BMC_RESET_N")
		)
		(pad "3" smd rect
			(at -0.65024 -0.8255)
			(size 0.4064 1.2192)
			(layers "F.Cu" "F.Mask" "F.Paste")
			(net "GND")
		)
		(pad "4" smd rect
			(at -0.65024 0.8255)
			(size 0.4064 1.2192)
			(layers "F.Cu" "F.Mask" "F.Paste")
			(net "FM_TPM_PRES_RST_N_C")
		)
		(pad "5" smd rect
			(at 0.65024 0.8255)
			(size 0.4064 1.2192)
			(layers "F.Cu" "F.Mask" "F.Paste")
			(net "P3V3_STBY")
		)
	)
	(footprint ""
		(layer "F.Cu")
		(at 78.938628 -74.5617 90)
		(property "Reference" "R962"
			(at 0 0 90)
			(layer "F.SilkS")
			(hide yes)
			(effects
				(font
					(size 1.27 1.27)
				)
			)
		)
		(property "Value" "4K7R2F-GP"
			(at 0.064008 -3.993896 90)
			(unlocked yes)
			(layer "F.Fab")
			(hide yes)
			(effects
				(font
					(size 1.016 1.016)
					(thickness 0.1524)
				)
			)
		)
		(property "Device Type" "R402H16"
			(at 0.064008 -5.517896 90)
			(unlocked yes)
			(layer "F.Fab")
			(hide yes)
			(effects
				(font
					(size 1.016 1.016)
					(thickness 0.1524)
				)
			)
		)
		(duplicate_pad_numbers_are_jumpers no)
		(fp_line
			(start 0.508 -0.9398)
			(end -0.508 -0.9398)
			(stroke
				(width 0.1524)
				(type default)
			)
			(layer "F.SilkS")
		)
		(fp_line
			(start -0.508 -0.9398)
			(end -0.508 0.9398)
			(stroke
				(width 0.1524)
				(type default)
			)
			(layer "F.SilkS")
		)
		(fp_rect
			(start -0.508 0.9398)
			(end 0.508 -0.9398)
			(stroke
				(width 0)
				(type default)
			)
			(fill no)
			(layer "F.CrtYd")
		)
		(fp_rect
			(start -0.508 0.9398)
			(end 0.508 -0.9398)
			(stroke
				(width 0)
				(type default)
			)
			(fill no)
			(layer "F.Fab")
		)
		(pad "1" smd custom
			(at 0 -0.4445 90)
			(size 0.1397 0.1397)
			(layers "F.Cu" "F.Mask" "F.Paste")
			(net "FLA_CS_R")
			(options
				(clearance outline)
				(anchor circle)
			)
			(primitives
				(gr_poly
					(pts
						(arc
							(start -0.1778 -0.2794)
							(mid -0.249642 -0.249642)
							(end -0.2794 -0.1778)
						)
						(arc
							(start -0.2794 0.1778)
							(mid -0.249642 0.249642)
							(end -0.1778 0.2794)
						)
						(arc
							(start 0.1778 0.2794)
							(mid 0.249642 0.249642)
							(end 0.2794 0.1778)
						)
						(arc
							(start 0.2794 -0.1778)
							(mid 0.249642 -0.249642)
							(end 0.1778 -0.2794)
						)
					)
					(width 0)
					(fill yes)
				)
			)
		)
		(pad "2" smd custom
			(at 0 0.4445 90)
			(size 0.1397 0.1397)
			(layers "F.Cu" "F.Mask" "F.Paste")
			(net "P3V3_STBY")
			(options
				(clearance outline)
				(anchor circle)
			)
			(primitives
				(gr_poly
					(pts
						(arc
							(start -0.1778 -0.2794)
							(mid -0.249642 -0.249642)
							(end -0.2794 -0.1778)
						)
						(arc
							(start -0.2794 0.1778)
							(mid -0.249642 0.249642)
							(end -0.1778 0.2794)
						)
						(arc
							(start 0.1778 0.2794)
							(mid 0.249642 0.249642)
							(end 0.2794 0.1778)
						)
						(arc
							(start 0.2794 -0.1778)
							(mid 0.249642 -0.249642)
							(end 0.1778 -0.2794)
						)
					)
					(width 0)
					(fill yes)
				)
			)
		)
	)
	(footprint ""
		(layer "F.Cu")
		(at 7.0612 -175.6156 90)
		(property "Reference" "Q95"
			(at 0 0 90)
			(layer "F.SilkS")
			(hide yes)
			(effects
				(font
					(size 1.27 1.27)
				)
			)
		)
		(property "Value" "2N7002K-1-GP"
			(at 0.127 -8.9662 90)
			(unlocked yes)
			(layer "F.Fab")
			(hide yes)
			(effects
				(font
					(size 1.016 1.016)
					(thickness 0.1524)
				)
			)
		)
		(property "Device Type" "SOT23DGS2D4H44"
			(at 0.127 -10.4902 90)
			(unlocked yes)
			(layer "F.Fab")
			(hide yes)
			(effects
				(font
					(size 1.016 1.016)
					(thickness 0.1524)
				)
			)
		)
		(duplicate_pad_numbers_are_jumpers no)
		(fp_line
			(start 1.651 -1.778)
			(end -1.651 -1.778)
			(stroke
				(width 0.1524)
				(type default)
			)
			(layer "F.SilkS")
		)
		(fp_line
			(start -1.651 -1.778)
			(end -1.651 1.778)
			(stroke
				(width 0.1524)
				(type default)
			)
			(layer "F.SilkS")
		)
		(fp_line
			(start 1.651 1.778)
			(end 1.651 -1.778)
			(stroke
				(width 0.1524)
				(type default)
			)
			(layer "F.SilkS")
		)
		(fp_line
			(start -1.651 1.778)
			(end 1.651 1.778)
			(stroke
				(width 0.1524)
				(type default)
			)
			(layer "F.SilkS")
		)
		(fp_poly
			(pts
				(xy -1.778 1.8796) (xy -1.778 -1.8796) (xy 1.778 -1.8796) (xy 1.778 1.8796)
			)
			(stroke
				(width 0)
				(type default)
			)
			(fill no)
			(layer "F.CrtYd")
		)
		(fp_poly
			(pts
				(xy -1.778 1.8796) (xy -1.778 -1.8796) (xy 1.778 -1.8796) (xy 1.778 1.8796)
			)
			(stroke
				(width 0)
				(type default)
			)
			(fill no)
			(layer "F.Fab")
		)
		(pad "D" smd custom
			(at 0 -0.9525 90)
			(size 0.1905 0.1905)
			(layers "F.Cu" "F.Mask" "F.Paste")
			(net "Q95_D")
			(options
				(clearance outline)
				(anchor circle)
			)
			(primitives
				(gr_poly
					(pts
						(arc
							(start -0.1778 0.5715)
							(mid -0.321484 0.511984)
							(end -0.381 0.3683)
						)
						(arc
							(start -0.381 -0.3683)
							(mid -0.321484 -0.511984)
							(end -0.1778 -0.5715)
						)
						(arc
							(start 0.1778 -0.5715)
							(mid 0.321484 -0.511984)
							(end 0.381 -0.3683)
						)
						(arc
							(start 0.381 0.3683)
							(mid 0.321484 0.511984)
							(end 0.1778 0.5715)
						)
					)
					(width 0)
					(fill yes)
				)
			)
		)
		(pad "G" smd custom
			(at -0.98425 0.9525 90)
			(size 0.1905 0.1905)
			(layers "F.Cu" "F.Mask" "F.Paste")
			(net "Q95_G")
			(options
				(clearance outline)
				(anchor circle)
			)
			(primitives
				(gr_poly
					(pts
						(arc
							(start -0.1778 0.5715)
							(mid -0.321484 0.511984)
							(end -0.381 0.3683)
						)
						(arc
							(start -0.381 -0.3683)
							(mid -0.321484 -0.511984)
							(end -0.1778 -0.5715)
						)
						(arc
							(start 0.1778 -0.5715)
							(mid 0.321484 -0.511984)
							(end 0.381 -0.3683)
						)
						(arc
							(start 0.381 0.3683)
							(mid 0.321484 0.511984)
							(end 0.1778 0.5715)
						)
					)
					(width 0)
					(fill yes)
				)
			)
		)
		(pad "S" smd custom
			(at 0.98425 0.9525 90)
			(size 0.1905 0.1905)
			(layers "F.Cu" "F.Mask" "F.Paste")
			(net "GND")
			(options
				(clearance outline)
				(anchor circle)
			)
			(primitives
				(gr_poly
					(pts
						(arc
							(start -0.1778 0.5715)
							(mid -0.321484 0.511984)
							(end -0.381 0.3683)
						)
						(arc
							(start -0.381 -0.3683)
							(mid -0.321484 -0.511984)
							(end -0.1778 -0.5715)
						)
						(arc
							(start 0.1778 -0.5715)
							(mid 0.321484 -0.511984)
							(end 0.381 -0.3683)
						)
						(arc
							(start 0.381 0.3683)
							(mid 0.321484 0.511984)
							(end 0.1778 0.5715)
						)
					)
					(width 0)
					(fill yes)
				)
			)
		)
	)
	(footprint ""
		(layer "F.Cu")
		(at 26.035 -76.9366 -90)
		(property "Reference" "R392"
			(at 0 0 270)
			(layer "F.SilkS")
			(hide yes)
			(effects
				(font
					(size 1.27 1.27)
				)
			)
		)
		(property "Value" "10KR2F-2-GP"
			(at 0.064008 -3.993896 270)
			(unlocked yes)
			(layer "F.Fab")
			(hide yes)
			(effects
				(font
					(size 1.016 1.016)
					(thickness 0.1524)
				)
			)
		)
		(property "Device Type" "R402H16"
			(at 0.064008 -5.517896 270)
			(unlocked yes)
			(layer "F.Fab")
			(hide yes)
			(effects
				(font
					(size 1.016 1.016)
					(thickness 0.1524)
				)
			)
		)
		(duplicate_pad_numbers_are_jumpers no)
		(fp_line
			(start -0.508 -0.9398)
			(end -0.508 0.9398)
			(stroke
				(width 0.1524)
				(type default)
			)
			(layer "F.SilkS")
		)
		(fp_line
			(start 0.508 -0.9398)
			(end -0.508 -0.9398)
			(stroke
				(width 0.1524)
				(type default)
			)
			(layer "F.SilkS")
		)
		(fp_rect
			(start -0.508 0.9398)
			(end 0.508 -0.9398)
			(stroke
				(width 0)
				(type default)
			)
			(fill no)
			(layer "F.CrtYd")
		)
		(fp_rect
			(start -0.508 0.9398)
			(end 0.508 -0.9398)
			(stroke
				(width 0)
				(type default)
			)
			(fill no)
			(layer "F.Fab")
		)
		(pad "1" smd custom
			(at 0 -0.4445 270)
			(size 0.1397 0.1397)
			(layers "F.Cu" "F.Mask" "F.Paste")
			(net "P3V3_STBY")
			(options
				(clearance outline)
				(anchor circle)
			)
			(primitives
				(gr_poly
					(pts
						(arc
							(start -0.1778 -0.2794)
							(mid -0.249642 -0.249642)
							(end -0.2794 -0.1778)
						)
						(arc
							(start -0.2794 0.1778)
							(mid -0.249642 0.249642)
							(end -0.1778 0.2794)
						)
						(arc
							(start 0.1778 0.2794)
							(mid 0.249642 0.249642)
							(end 0.2794 0.1778)
						)
						(arc
							(start 0.2794 -0.1778)
							(mid 0.249642 -0.249642)
							(end 0.1778 -0.2794)
						)
					)
					(width 0)
					(fill yes)
				)
			)
		)
		(pad "2" smd custom
			(at 0 0.4445 270)
			(size 0.1397 0.1397)
			(layers "F.Cu" "F.Mask" "F.Paste")
			(net "RMII_BMC_PHY_TXD0")
			(options
				(clearance outline)
				(anchor circle)
			)
			(primitives
				(gr_poly
					(pts
						(arc
							(start -0.1778 -0.2794)
							(mid -0.249642 -0.249642)
							(end -0.2794 -0.1778)
						)
						(arc
							(start -0.2794 0.1778)
							(mid -0.249642 0.249642)
							(end -0.1778 0.2794)
						)
						(arc
							(start 0.1778 0.2794)
							(mid 0.249642 0.249642)
							(end 0.2794 0.1778)
						)
						(arc
							(start 0.2794 -0.1778)
							(mid 0.249642 -0.249642)
							(end 0.1778 -0.2794)
						)
					)
					(width 0)
					(fill yes)
				)
			)
		)
	)
	(footprint ""
		(layer "F.Cu")
		(at 310.007 -63.9826)
		(property "Reference" "PG51"
			(at 0 0 0)
			(layer "F.SilkS")
			(hide yes)
			(effects
				(font
					(size 1.27 1.27)
				)
			)
		)
		(property "Value" "GAP-CLOSE-PWR-3-GP"
			(at 0.0254 -6.5786 0)
			(unlocked yes)
			(layer "F.Fab")
			(hide yes)
			(effects
				(font
					(size 1.016 1.016)
					(thickness 0.1524)
				)
			)
		)
		(property "Device Type" "GAP-CLOSE-PWR-3"
			(at 0.0254 -8.255 0)
			(unlocked yes)
			(layer "F.Fab")
			(hide yes)
			(effects
				(font
					(size 1.016 1.016)
					(thickness 0.1524)
				)
			)
		)
		(duplicate_pad_numbers_are_jumpers no)
		(fp_rect
			(start -0.7112 0.4572)
			(end 0.7112 -0.4572)
			(stroke
				(width 0)
				(type default)
			)
			(fill no)
			(layer "F.CrtYd")
		)
		(fp_poly
			(pts
				(xy -0.7112 -0.4572) (xy 0.7112 -0.4572) (xy 0.7112 0.4572) (xy -0.7112 0.4572)
			)
			(stroke
				(width 0)
				(type default)
			)
			(fill no)
			(layer "F.Fab")
		)
		(pad "1" smd rect
			(at -0.3048 0)
			(size 0.6604 0.762)
			(layers "F.Cu" "F.Mask" "F.Paste")
			(net "DUT_VDD")
		)
		(pad "2" smd rect
			(at 0.3048 0)
			(size 0.6604 0.762)
			(layers "F.Cu" "F.Mask" "F.Paste")
			(net "P0V9_E")
		)
	)
)
